(kicad_pcb
	(version 20260206)
	(generator "pcbnew")
	(generator_version "10.0")
	(general
		(thickness 1.6)
		(legacy_teardrops no)
	)
	(paper "A4")
	(title_block
		(title "Wiwynn_Tioga_Pass_MB.brd")
		(comment 1 "Tioga Pass / footprints 2769-2775 of 4770")
	)
	(layers
		(0 "F.Cu" signal "TOP")
		(4 "In1.Cu" signal "L2GND")
		(6 "In2.Cu" signal "L3")
		(8 "In3.Cu" signal "L4GND")
		(10 "In4.Cu" signal "L5")
		(12 "In5.Cu" signal "L6GND")
		(14 "In6.Cu" signal "L7VCC")
		(16 "In7.Cu" signal "L8VCC")
		(18 "In8.Cu" signal "L9GND")
		(20 "In9.Cu" signal "L10")
		(22 "In10.Cu" signal "L11GND")
		(24 "In11.Cu" signal "L12")
		(26 "In12.Cu" signal "L13GND")
		(2 "B.Cu" signal "BOTTOM")
		(9 "F.Adhes" user "F.Adhesive")
		(11 "B.Adhes" user "B.Adhesive")
		(13 "F.Paste" user "Package Geometry/Pastemask Top")
		(15 "B.Paste" user "Package Geometry/Pastemask Bottom")
		(5 "F.SilkS" user "Ref Des/Silkscreen Top")
		(7 "B.SilkS" user "Ref Des/Silkscreen Bottom")
		(1 "F.Mask" user "Board Geometry/Soldermask Top")
		(3 "B.Mask" user "Board Geometry/Soldermask Bottom")
		(17 "Dwgs.User" user "User.Drawings")
		(19 "Cmts.User" user "User.Comments")
		(21 "Eco1.User" user "User.Eco1")
		(23 "Eco2.User" user "User.Eco2")
		(25 "Edge.Cuts" user "Board Geometry/Outline")
		(27 "Margin" user)
		(31 "F.CrtYd" user "Package Geometry/Place Bound Top")
		(29 "B.CrtYd" user "Package Geometry/Place Bound Bottom")
		(35 "F.Fab" user "Ref Des/Assembly Top")
		(33 "B.Fab" user "Ref Des/Assembly Bottom")
	)
	(footprint ""
		(layer "B.Cu")
		(at 490.3851 -120.7516 90)
		(property "Reference" "R9G13"
			(at 0 0 90)
			(layer "B.SilkS")
			(hide yes)
			(effects
				(font
					(size 1.27 1.27)
				)
				(justify mirror)
			)
		)
		(property "Value" ""
			(at 0 0 90)
			(layer "B.Fab")
			(effects
				(font
					(size 1.27 1.27)
				)
				(justify mirror)
			)
		)
		(duplicate_pad_numbers_are_jumpers no)
		(fp_poly
			(pts
				(xy 0.2794 -0.1016) (xy -0.2794 -0.1016) (xy -0.2794 0.9906) (xy 0.2794 0.9906)
			)
			(stroke
				(width 0)
				(type default)
			)
			(fill no)
			(layer "B.CrtYd")
		)
		(fp_line
			(start 0.2794 -0.1016)
			(end 0.2794 0.9906)
			(stroke
				(width 0.1)
				(type default)
			)
			(layer "B.Fab")
		)
		(fp_line
			(start -0.2794 -0.1016)
			(end 0.2794 -0.1016)
			(stroke
				(width 0.1)
				(type default)
			)
			(layer "B.Fab")
		)
		(fp_line
			(start 0.2794 0.9906)
			(end -0.2794 0.9906)
			(stroke
				(width 0.1)
				(type default)
			)
			(layer "B.Fab")
		)
		(fp_line
			(start -0.2794 0.9906)
			(end -0.2794 -0.1016)
			(stroke
				(width 0.1)
				(type default)
			)
			(layer "B.Fab")
		)
		(pad "1" smd rect
			(at 0 0 270)
			(size 0.508 0.508)
			(layers "B.Cu" "B.Mask" "B.Paste")
			(net "SMB_OCP_LAN_STBY_LVC3_SCL")
		)
		(pad "2" smd rect
			(at 0 0.889 270)
			(size 0.508 0.508)
			(layers "B.Cu" "B.Mask" "B.Paste")
			(net "SMB_SPRINGVILLE_STBY_LVC3_SCL")
		)
		(zone
			(layer "B.Cu")
			(hatch none 0.5)
			(connect_pads
				(clearance 0)
			)
			(min_thickness 0.25)
			(keepout
				(tracks allowed)
				(vias not_allowed)
				(pads allowed)
				(copperpour not_allowed)
				(footprints allowed)
			)
			(placement
				(enabled no)
				(sheetname "")
			)
			(fill
				(thermal_gap 0.5)
				(thermal_bridge_width 0.5)
				(island_removal_mode 0)
			)
			(polygon
				(pts
					(xy 490.6391 -121.0056) (xy 490.6391 -120.4976) (xy 491.0201 -120.4976) (xy 491.0201 -121.0056)
				)
			)
		)
		(zone
			(layer "B.Cu")
			(hatch none 0.5)
			(connect_pads
				(clearance 0)
			)
			(min_thickness 0.25)
			(keepout
				(tracks not_allowed)
				(vias allowed)
				(pads allowed)
				(copperpour not_allowed)
				(footprints allowed)
			)
			(placement
				(enabled no)
				(sheetname "")
			)
			(fill
				(thermal_gap 0.5)
				(thermal_bridge_width 0.5)
				(island_removal_mode 0)
			)
			(polygon
				(pts
					(xy 491.0201 -121.0056) (xy 491.0201 -120.4976) (xy 490.6391 -120.4976) (xy 490.6391 -121.0056)
				)
			)
		)
	)
	(footprint ""
		(layer "B.Cu")
		(at 408.051 -4.3815 180)
		(property "Reference" "R8D39"
			(at 0 0 0)
			(layer "B.SilkS")
			(hide yes)
			(effects
				(font
					(size 1.27 1.27)
				)
				(justify mirror)
			)
		)
		(property "Value" ""
			(at 0 0 0)
			(layer "B.Fab")
			(effects
				(font
					(size 1.27 1.27)
				)
				(justify mirror)
			)
		)
		(duplicate_pad_numbers_are_jumpers no)
		(fp_poly
			(pts
				(xy 0.2794 -0.1016) (xy -0.2794 -0.1016) (xy -0.2794 0.9906) (xy 0.2794 0.9906)
			)
			(stroke
				(width 0)
				(type default)
			)
			(fill no)
			(layer "B.CrtYd")
		)
		(fp_line
			(start 0.2794 0.9906)
			(end -0.2794 0.9906)
			(stroke
				(width 0.1)
				(type default)
			)
			(layer "B.Fab")
		)
		(fp_line
			(start 0.2794 -0.1016)
			(end 0.2794 0.9906)
			(stroke
				(width 0.1)
				(type default)
			)
			(layer "B.Fab")
		)
		(fp_line
			(start -0.2794 0.9906)
			(end -0.2794 -0.1016)
			(stroke
				(width 0.1)
				(type default)
			)
			(layer "B.Fab")
		)
		(fp_line
			(start -0.2794 -0.1016)
			(end 0.2794 -0.1016)
			(stroke
				(width 0.1)
				(type default)
			)
			(layer "B.Fab")
		)
		(pad "1" smd rect
			(at 0 0)
			(size 0.508 0.508)
			(layers "B.Cu" "B.Mask" "B.Paste")
			(net "P5V")
		)
		(pad "2" smd rect
			(at 0 0.889)
			(size 0.508 0.508)
			(layers "B.Cu" "B.Mask" "B.Paste")
			(net "A_PG_P5V")
		)
		(zone
			(layer "B.Cu")
			(hatch none 0.5)
			(connect_pads
				(clearance 0)
			)
			(min_thickness 0.25)
			(keepout
				(tracks not_allowed)
				(vias allowed)
				(pads allowed)
				(copperpour not_allowed)
				(footprints allowed)
			)
			(placement
				(enabled no)
				(sheetname "")
			)
			(fill
				(thermal_gap 0.5)
				(thermal_bridge_width 0.5)
				(island_removal_mode 0)
			)
			(polygon
				(pts
					(xy 407.797 -5.0165) (xy 408.305 -5.0165) (xy 408.305 -4.6355) (xy 407.797 -4.6355)
				)
			)
		)
		(zone
			(layer "B.Cu")
			(hatch none 0.5)
			(connect_pads
				(clearance 0)
			)
			(min_thickness 0.25)
			(keepout
				(tracks allowed)
				(vias not_allowed)
				(pads allowed)
				(copperpour not_allowed)
				(footprints allowed)
			)
			(placement
				(enabled no)
				(sheetname "")
			)
			(fill
				(thermal_gap 0.5)
				(thermal_bridge_width 0.5)
				(island_removal_mode 0)
			)
			(polygon
				(pts
					(xy 407.797 -4.6355) (xy 408.305 -4.6355) (xy 408.305 -5.0165) (xy 407.797 -5.0165)
				)
			)
		)
	)
	(footprint ""
		(layer "B.Cu")
		(at 381.7112 -90.53068 180)
		(property "Reference" "R7W13"
			(at 0.8382 -0.67818 180)
			(unlocked yes)
			(layer "B.SilkS")
			(effects
				(font
					(size 0.4064 0.254)
					(thickness 0.1524)
				)
				(justify left mirror)
			)
		)
		(property "Value" ""
			(at 0 0 0)
			(layer "B.Fab")
			(effects
				(font
					(size 1.27 1.27)
				)
				(justify mirror)
			)
		)
		(duplicate_pad_numbers_are_jumpers no)
		(fp_poly
			(pts
				(xy 0.2794 -0.1016) (xy -0.2794 -0.1016) (xy -0.2794 0.9906) (xy 0.2794 0.9906)
			)
			(stroke
				(width 0)
				(type default)
			)
			(fill no)
			(layer "B.CrtYd")
		)
		(fp_line
			(start 0.2794 0.9906)
			(end -0.2794 0.9906)
			(stroke
				(width 0.1)
				(type default)
			)
			(layer "B.Fab")
		)
		(fp_line
			(start 0.2794 -0.1016)
			(end 0.2794 0.9906)
			(stroke
				(width 0.1)
				(type default)
			)
			(layer "B.Fab")
		)
		(fp_line
			(start -0.2794 0.9906)
			(end -0.2794 -0.1016)
			(stroke
				(width 0.1)
				(type default)
			)
			(layer "B.Fab")
		)
		(fp_line
			(start -0.2794 -0.1016)
			(end 0.2794 -0.1016)
			(stroke
				(width 0.1)
				(type default)
			)
			(layer "B.Fab")
		)
		(pad "1" smd rect
			(at 0 0)
			(size 0.508 0.508)
			(layers "B.Cu" "B.Mask" "B.Paste")
			(net "FM_BMC_READY_N")
		)
		(pad "2" smd rect
			(at 0 0.889)
			(size 0.508 0.508)
			(layers "B.Cu" "B.Mask" "B.Paste")
			(net "FM_BMC_READY_R_N")
		)
		(zone
			(layer "B.Cu")
			(hatch none 0.5)
			(connect_pads
				(clearance 0)
			)
			(min_thickness 0.25)
			(keepout
				(tracks not_allowed)
				(vias allowed)
				(pads allowed)
				(copperpour not_allowed)
				(footprints allowed)
			)
			(placement
				(enabled no)
				(sheetname "")
			)
			(fill
				(thermal_gap 0.5)
				(thermal_bridge_width 0.5)
				(island_removal_mode 0)
			)
			(polygon
				(pts
					(xy 381.4572 -91.16568) (xy 381.9652 -91.16568) (xy 381.9652 -90.78468) (xy 381.4572 -90.78468)
				)
			)
		)
		(zone
			(layer "B.Cu")
			(hatch none 0.5)
			(connect_pads
				(clearance 0)
			)
			(min_thickness 0.25)
			(keepout
				(tracks allowed)
				(vias not_allowed)
				(pads allowed)
				(copperpour not_allowed)
				(footprints allowed)
			)
			(placement
				(enabled no)
				(sheetname "")
			)
			(fill
				(thermal_gap 0.5)
				(thermal_bridge_width 0.5)
				(island_removal_mode 0)
			)
			(polygon
				(pts
					(xy 381.4572 -90.78468) (xy 381.9652 -90.78468) (xy 381.9652 -91.16568) (xy 381.4572 -91.16568)
				)
			)
		)
	)
	(footprint ""
		(layer "B.Cu")
		(at 80.757268 -135.4074 -90)
		(property "Reference" "C8M6"
			(at -1.848866 0.752348 270)
			(unlocked yes)
			(layer "B.SilkS")
			(effects
				(font
					(size 1.27 0.9652)
					(thickness 0.1524)
				)
				(justify mirror)
			)
		)
		(property "Value" ""
			(at 0 0 90)
			(layer "B.Fab")
			(effects
				(font
					(size 1.27 1.27)
				)
				(justify mirror)
			)
		)
		(duplicate_pad_numbers_are_jumpers no)
		(fp_rect
			(start 0.500126 1.598422)
			(end -0.500126 -0.201422)
			(stroke
				(width 0)
				(type default)
			)
			(fill no)
			(layer "B.CrtYd")
		)
		(fp_line
			(start -0.500126 1.598422)
			(end 0.500126 1.598422)
			(stroke
				(width 0.1)
				(type default)
			)
			(layer "B.Fab")
		)
		(fp_line
			(start 0.500126 1.598422)
			(end 0.500126 -0.201422)
			(stroke
				(width 0.1)
				(type default)
			)
			(layer "B.Fab")
		)
		(fp_line
			(start -0.500126 -0.201422)
			(end -0.500126 1.598422)
			(stroke
				(width 0.1)
				(type default)
			)
			(layer "B.Fab")
		)
		(fp_line
			(start 0.500126 -0.201422)
			(end -0.500126 -0.201422)
			(stroke
				(width 0.1)
				(type default)
			)
			(layer "B.Fab")
		)
		(pad "1" smd rect
			(at 0 0 180)
			(size 0.889 0.9906)
			(layers "B.Cu" "B.Mask" "B.Paste")
			(net "PVDDQ_KLM")
		)
		(pad "2" smd rect
			(at 0 1.397 180)
			(size 0.889 0.9906)
			(layers "B.Cu" "B.Mask" "B.Paste")
			(net "GND")
		)
		(zone
			(layer "B.Cu")
			(hatch none 0.5)
			(connect_pads
				(clearance 0)
			)
			(min_thickness 0.25)
			(keepout
				(tracks allowed)
				(vias not_allowed)
				(pads allowed)
				(copperpour not_allowed)
				(footprints allowed)
			)
			(placement
				(enabled no)
				(sheetname "")
			)
			(fill
				(thermal_gap 0.5)
				(thermal_bridge_width 0.5)
				(island_removal_mode 0)
			)
			(polygon
				(pts
					(xy 79.804768 -134.9121) (xy 80.312768 -134.9121) (xy 80.312768 -135.9027) (xy 79.804768 -135.9027)
				)
			)
		)
		(zone
			(layer "B.Cu")
			(hatch none 0.5)
			(connect_pads
				(clearance 0)
			)
			(min_thickness 0.25)
			(keepout
				(tracks not_allowed)
				(vias allowed)
				(pads allowed)
				(copperpour not_allowed)
				(footprints allowed)
			)
			(placement
				(enabled no)
				(sheetname "")
			)
			(fill
				(thermal_gap 0.5)
				(thermal_bridge_width 0.5)
				(island_removal_mode 0)
			)
			(polygon
				(pts
					(xy 79.804768 -134.9121) (xy 80.312768 -134.9121) (xy 80.312768 -135.9027) (xy 79.804768 -135.9027)
				)
			)
		)
	)
	(footprint ""
		(layer "B.Cu")
		(at 484.124 -145.6182 90)
		(property "Reference" "CR1L3"
			(at 0 0 90)
			(layer "B.SilkS")
			(hide yes)
			(effects
				(font
					(size 1.27 1.27)
				)
				(justify mirror)
			)
		)
		(property "Value" ""
			(at 0 0 90)
			(layer "B.Fab")
			(effects
				(font
					(size 1.27 1.27)
				)
				(justify mirror)
			)
		)
		(duplicate_pad_numbers_are_jumpers no)
		(fp_line
			(start 0.9144 0.1016)
			(end 0.9144 2.9464)
			(stroke
				(width 0.1524)
				(type default)
			)
			(layer "B.SilkS")
		)
		(fp_line
			(start 0.8382 0.1016)
			(end 0.9144 0.1016)
			(stroke
				(width 0.1524)
				(type default)
			)
			(layer "B.SilkS")
		)
		(fp_line
			(start -0.8382 0.1016)
			(end -0.9144 0.1016)
			(stroke
				(width 0.1524)
				(type default)
			)
			(layer "B.SilkS")
		)
		(fp_line
			(start -0.9144 0.1016)
			(end -0.9144 2.9464)
			(stroke
				(width 0.1524)
				(type default)
			)
			(layer "B.SilkS")
		)
		(fp_line
			(start 0.9144 2.9464)
			(end 0.8382 2.9464)
			(stroke
				(width 0.1524)
				(type default)
			)
			(layer "B.SilkS")
		)
		(fp_line
			(start -0.9144 2.9464)
			(end -0.8382 2.9464)
			(stroke
				(width 0.1524)
				(type default)
			)
			(layer "B.SilkS")
		)
		(fp_circle
			(center -1.128776 -0.907288)
			(end -1.128776 -0.780288)
			(stroke
				(width 0.254)
				(type default)
			)
			(fill no)
			(layer "B.SilkS")
		)
		(fp_poly
			(pts
				(xy 0 0.1016) (xy -0.5334 0.1016) (xy -0.7366 0.1016) (xy -0.9144 0.1016) (xy -0.9144 2.9464) (xy -0.8382 2.9464)
				(xy -0.762 2.9464) (xy 0.9144 2.9464) (xy 0.9144 2.7686) (xy 0.9144 2.159) (xy 0.9144 0.1016) (xy 0.7366 0.1016)
				(xy 0.5842 0.1016)
			)
			(stroke
				(width 0)
				(type default)
			)
			(fill no)
			(layer "B.CrtYd")
		)
		(fp_line
			(start 0.9144 0.1016)
			(end 0.9144 2.9464)
			(stroke
				(width 0.1)
				(type default)
			)
			(layer "B.Fab")
		)
		(fp_line
			(start -0.9144 0.1016)
			(end 0.9144 0.1016)
			(stroke
				(width 0.1)
				(type default)
			)
			(layer "B.Fab")
		)
		(fp_line
			(start 0.9144 2.9464)
			(end -0.9144 2.9464)
			(stroke
				(width 0.1)
				(type default)
			)
			(layer "B.Fab")
		)
		(fp_line
			(start -0.9144 2.9464)
			(end -0.9144 0.1016)
			(stroke
				(width 0.1)
				(type default)
			)
			(layer "B.Fab")
		)
		(fp_circle
			(center -1.128776 -0.907288)
			(end -1.128776 -0.780288)
			(stroke
				(width 0.254)
				(type default)
			)
			(fill no)
			(layer "B.Fab")
		)
		(pad "1" smd rect
			(at 0 0)
			(size 1.524 0.762)
			(layers "B.Cu" "B.Mask" "B.Paste")
			(net "FM_DB_UART_SEL3_N")
		)
		(pad "2" smd rect
			(at 0 3.048 180)
			(size 1.524 0.762)
			(layers "B.Cu" "B.Mask" "B.Paste")
			(net "FM_DB_UART_SEL2_N")
		)
	)
	(footprint ""
		(layer "B.Cu")
		(at 337.537806 -61.257434)
		(property "Reference" "C2U6"
			(at 0 0 0)
			(layer "B.SilkS")
			(hide yes)
			(effects
				(font
					(size 1.27 1.27)
				)
				(justify mirror)
			)
		)
		(property "Value" ""
			(at 0 0 0)
			(layer "B.Fab")
			(effects
				(font
					(size 1.27 1.27)
				)
				(justify mirror)
			)
		)
		(duplicate_pad_numbers_are_jumpers no)
		(fp_poly
			(pts
				(xy -0.3048 -0.1016) (xy -0.3048 0.9906) (xy 0.3048 0.9906) (xy 0.3048 -0.1016)
			)
			(stroke
				(width 0)
				(type default)
			)
			(fill no)
			(layer "B.CrtYd")
		)
		(fp_line
			(start -0.3048 -0.1016)
			(end 0.3048 -0.1016)
			(stroke
				(width 0.1)
				(type default)
			)
			(layer "B.Fab")
		)
		(fp_line
			(start -0.3048 0.9906)
			(end -0.3048 -0.1016)
			(stroke
				(width 0.1)
				(type default)
			)
			(layer "B.Fab")
		)
		(fp_line
			(start 0.3048 -0.1016)
			(end 0.3048 0.9906)
			(stroke
				(width 0.1)
				(type default)
			)
			(layer "B.Fab")
		)
		(fp_line
			(start 0.3048 0.9906)
			(end -0.3048 0.9906)
			(stroke
				(width 0.1)
				(type default)
			)
			(layer "B.Fab")
		)
		(pad "1" smd rect
			(at 0 0 180)
			(size 0.508 0.508)
			(layers "B.Cu" "B.Mask" "B.Paste")
			(net "P3E_CPU0_PE1_PCH_RXN<1>")
		)
		(pad "2" smd rect
			(at 0 0.889 180)
			(size 0.508 0.508)
			(layers "B.Cu" "B.Mask" "B.Paste")
			(net "P3E_CPU0_PE1_SS_RXN<1>")
		)
		(zone
			(layer "B.Cu")
			(hatch none 0.5)
			(connect_pads
				(clearance 0)
			)
			(min_thickness 0.25)
			(keepout
				(tracks allowed)
				(vias not_allowed)
				(pads allowed)
				(copperpour not_allowed)
				(footprints allowed)
			)
			(placement
				(enabled no)
				(sheetname "")
			)
			(fill
				(thermal_gap 0.5)
				(thermal_bridge_width 0.5)
				(island_removal_mode 0)
			)
			(polygon
				(pts
					(xy 337.791806 -61.003434) (xy 337.283806 -61.003434) (xy 337.283806 -60.622434) (xy 337.791806 -60.622434)
				)
			)
		)
		(zone
			(layer "B.Cu")
			(hatch none 0.5)
			(connect_pads
				(clearance 0)
			)
			(min_thickness 0.25)
			(keepout
				(tracks not_allowed)
				(vias allowed)
				(pads allowed)
				(copperpour not_allowed)
				(footprints allowed)
			)
			(placement
				(enabled no)
				(sheetname "")
			)
			(fill
				(thermal_gap 0.5)
				(thermal_bridge_width 0.5)
				(island_removal_mode 0)
			)
			(polygon
				(pts
					(xy 337.791806 -60.622434) (xy 337.283806 -60.622434) (xy 337.283806 -61.003434) (xy 337.791806 -61.003434)
				)
			)
		)
	)
	(footprint ""
		(layer "B.Cu")
		(at 489.26496 -151.06904 90)
		(property "Reference" "R1L19"
			(at 0 0 90)
			(layer "B.SilkS")
			(hide yes)
			(effects
				(font
					(size 1.27 1.27)
				)
				(justify mirror)
			)
		)
		(property "Value" ""
			(at 0 0 90)
			(layer "B.Fab")
			(effects
				(font
					(size 1.27 1.27)
				)
				(justify mirror)
			)
		)
		(duplicate_pad_numbers_are_jumpers no)
		(fp_poly
			(pts
				(xy 0.2794 -0.1016) (xy -0.2794 -0.1016) (xy -0.2794 0.9906) (xy 0.2794 0.9906)
			)
			(stroke
				(width 0)
				(type default)
			)
			(fill no)
			(layer "B.CrtYd")
		)
		(fp_line
			(start 0.2794 -0.1016)
			(end 0.2794 0.9906)
			(stroke
				(width 0.1)
				(type default)
			)
			(layer "B.Fab")
		)
		(fp_line
			(start -0.2794 -0.1016)
			(end 0.2794 -0.1016)
			(stroke
				(width 0.1)
				(type default)
			)
			(layer "B.Fab")
		)
		(fp_line
			(start 0.2794 0.9906)
			(end -0.2794 0.9906)
			(stroke
				(width 0.1)
				(type default)
			)
			(layer "B.Fab")
		)
		(fp_line
			(start -0.2794 0.9906)
			(end -0.2794 -0.1016)
			(stroke
				(width 0.1)
				(type default)
			)
			(layer "B.Fab")
		)
		(pad "1" smd rect
			(at 0 0 270)
			(size 0.508 0.508)
			(layers "B.Cu" "B.Mask" "B.Paste")
			(net "P3V3_STBY")
		)
		(pad "2" smd rect
			(at 0 0.889 270)
			(size 0.508 0.508)
			(layers "B.Cu" "B.Mask" "B.Paste")
			(net "FM_DEBUG_RST_BTN_N")
		)
		(zone
			(layer "B.Cu")
			(hatch none 0.5)
			(connect_pads
				(clearance 0)
			)
			(min_thickness 0.25)
			(keepout
				(tracks allowed)
				(vias not_allowed)
				(pads allowed)
				(copperpour not_allowed)
				(footprints allowed)
			)
			(placement
				(enabled no)
				(sheetname "")
			)
			(fill
				(thermal_gap 0.5)
				(thermal_bridge_width 0.5)
				(island_removal_mode 0)
			)
			(polygon
				(pts
					(xy 489.51896 -151.32304) (xy 489.51896 -150.81504) (xy 489.89996 -150.81504) (xy 489.89996 -151.32304)
				)
			)
		)
		(zone
			(layer "B.Cu")
			(hatch none 0.5)
			(connect_pads
				(clearance 0)
			)
			(min_thickness 0.25)
			(keepout
				(tracks not_allowed)
				(vias allowed)
				(pads allowed)
				(copperpour not_allowed)
				(footprints allowed)
			)
			(placement
				(enabled no)
				(sheetname "")
			)
			(fill
				(thermal_gap 0.5)
				(thermal_bridge_width 0.5)
				(island_removal_mode 0)
			)
			(polygon
				(pts
					(xy 489.89996 -151.32304) (xy 489.89996 -150.81504) (xy 489.51896 -150.81504) (xy 489.51896 -151.32304)
				)
			)
		)
	)
)
